(kicad_pcb
	(version 20260206)
	(generator "pcbnew")
	(generator_version "10.0")
	(general
		(thickness 1.6)
		(legacy_teardrops no)
	)
	(paper "A4")
	(title_block
		(title "04192023_DAF0TMB3IC0_F0TG_MB_C_brd_V02_OCP.brd")
		(comment 1 "Grand Teton / footprint 2783 of 8354 (U26), pads 4452-4560 of 6102")
	)
	(layers
		(0 "F.Cu" signal "TOP")
		(4 "In1.Cu" signal "GND")
		(6 "In2.Cu" signal "IN1")
		(8 "In3.Cu" signal "GND1")
		(10 "In4.Cu" signal "IN2")
		(12 "In5.Cu" signal "GND2")
		(14 "In6.Cu" signal "IN3")
		(16 "In7.Cu" signal "GND3")
		(18 "In8.Cu" signal "VCC")
		(20 "In9.Cu" signal "VCC1")
		(22 "In10.Cu" signal "GND4")
		(24 "In11.Cu" signal "IN4")
		(26 "In12.Cu" signal "GND5")
		(28 "In13.Cu" signal "IN5")
		(30 "In14.Cu" signal "GND6")
		(32 "In15.Cu" signal "IN6")
		(34 "In16.Cu" signal "GND7")
		(2 "B.Cu" signal "BOTTOM")
		(9 "F.Adhes" user "F.Adhesive")
		(11 "B.Adhes" user "B.Adhesive")
		(13 "F.Paste" user "Package Geometry/Pastemask Top")
		(15 "B.Paste" user "Package Geometry/Pastemask Bottom")
		(5 "F.SilkS" user "Ref Des/Silkscreen Top")
		(7 "B.SilkS" user "Ref Des/Silkscreen Bottom")
		(1 "F.Mask" user "Board Geometry/Soldermask Top")
		(3 "B.Mask" user "Board Geometry/Soldermask Bottom")
		(17 "Dwgs.User" user "User.Drawings")
		(19 "Cmts.User" user "User.Comments")
		(21 "Eco1.User" user "User.Eco1")
		(23 "Eco2.User" user "User.Eco2")
		(25 "Edge.Cuts" user "Board Geometry/Outline")
		(27 "Margin" user)
		(31 "F.CrtYd" user "Package Geometry/Place Bound Top")
		(29 "B.CrtYd" user "Package Geometry/Place Bound Bottom")
		(35 "F.Fab" user "Ref Des/Assembly Top")
		(33 "B.Fab" user "Ref Des/Assembly Bottom")
	)
	(footprint ""
		(layer "F.Cu")
		(at 111.927894 -258.880356 180)
		(property "Reference" "U26"
			(at -45.05579 -61.794136 0)
			(unlocked yes)
			(layer "F.SilkS")
			(effects
				(font
					(size 0.7874 0.5842)
					(thickness 0.1524)
				)
			)
		)
		(property "Value" ""
			(at 0 0 180)
			(layer "F.Fab")
			(effects
				(font
					(size 1.27 1.27)
				)
			)
		)
		(duplicate_pad_numbers_are_jumpers no)
		(pad "DB62" smd circle
			(at 22.409912 31.139892 180)
			(size 0.450088 0.450088)
			(layers "F.Cu" "F.Mask" "F.Paste")
			(net "M_B_CPU1_SB_DQ<27>")
		)
		(pad "DB63" smd circle
			(at 23.349966 31.139892 180)
			(size 0.450088 0.450088)
			(layers "F.Cu" "F.Mask" "F.Paste")
			(net "M_B_CPU1_SB_DQS_DP<3>")
		)
		(pad "DB64" smd circle
			(at 24.29002 31.139892 180)
			(size 0.450088 0.450088)
			(layers "F.Cu" "F.Mask" "F.Paste")
			(net "PVDDIO_P1")
		)
		(pad "DB65" smd circle
			(at 25.230074 31.139892 180)
			(size 0.450088 0.450088)
			(layers "F.Cu" "F.Mask" "F.Paste")
			(net "M_F_CPU1_SB_DQ<27>")
		)
		(pad "DB66" smd circle
			(at 26.170128 31.139892 180)
			(size 0.450088 0.450088)
			(layers "F.Cu" "F.Mask" "F.Paste")
			(net "GND")
		)
		(pad "DB67" smd circle
			(at 27.109928 31.139892 180)
			(size 0.450088 0.450088)
			(layers "F.Cu" "F.Mask" "F.Paste")
			(net "M_F_CPU1_SB_DQS_DP<3>")
		)
		(pad "DB68" smd circle
			(at 28.049982 31.139892 180)
			(size 0.450088 0.450088)
			(layers "F.Cu" "F.Mask" "F.Paste")
			(net "GND")
		)
		(pad "DB69" smd circle
			(at 28.990036 31.139892 180)
			(size 0.450088 0.450088)
			(layers "F.Cu" "F.Mask" "F.Paste")
			(net "M_E_CPU1_SB_DQ<27>")
		)
		(pad "DB70" smd circle
			(at 29.93009 31.139892 180)
			(size 0.450088 0.450088)
			(layers "F.Cu" "F.Mask" "F.Paste")
			(net "M_E_CPU1_SB_DQS_DP<3>")
		)
		(pad "DB71" smd circle
			(at 30.86989 31.139892 180)
			(size 0.450088 0.450088)
			(layers "F.Cu" "F.Mask" "F.Paste")
			(net "PVDDIO_P1")
		)
		(pad "DB72" smd circle
			(at 31.809944 31.139892 180)
			(size 0.450088 0.450088)
			(layers "F.Cu" "F.Mask" "F.Paste")
			(net "M_A_CPU1_SB_DQ<27>")
		)
		(pad "DB73" smd circle
			(at 32.749998 31.139892 180)
			(size 0.450088 0.450088)
			(layers "F.Cu" "F.Mask" "F.Paste")
			(net "GND")
		)
		(pad "DB74" smd circle
			(at 33.690052 31.139892 180)
			(size 0.450088 0.450088)
			(layers "F.Cu" "F.Mask" "F.Paste")
			(net "M_A_CPU1_SB_DQS_DP<3>")
		)
		(pad "DC1" smd circle
			(at -34.459926 31.949898 180)
			(size 0.450088 0.450088)
			(layers "F.Cu" "F.Mask" "F.Paste")
			(net "GND")
		)
		(pad "DC2" smd circle
			(at -33.519872 31.949898 180)
			(size 0.450088 0.450088)
			(layers "F.Cu" "F.Mask" "F.Paste")
			(net "M_G_CPU1_SB_DQS_DN<3>")
		)
		(pad "DC3" smd circle
			(at -32.580072 31.949898 180)
			(size 0.450088 0.450088)
			(layers "F.Cu" "F.Mask" "F.Paste")
			(net "M_G_CPU1_SB_DQS_DN<8>")
		)
		(pad "DC4" smd circle
			(at -31.640018 31.949898 180)
			(size 0.450088 0.450088)
			(layers "F.Cu" "F.Mask" "F.Paste")
			(net "GND")
		)
		(pad "DC5" smd circle
			(at -30.699964 31.949898 180)
			(size 0.450088 0.450088)
			(layers "F.Cu" "F.Mask" "F.Paste")
			(net "M_K_CPU1_SB_DQS_DN<3>")
		)
		(pad "DC6" smd circle
			(at -29.75991 31.949898 180)
			(size 0.450088 0.450088)
			(layers "F.Cu" "F.Mask" "F.Paste")
			(net "GND")
		)
		(pad "DC7" smd circle
			(at -28.82011 31.949898 180)
			(size 0.450088 0.450088)
			(layers "F.Cu" "F.Mask" "F.Paste")
			(net "M_K_CPU1_SB_DQS_DN<8>")
		)
		(pad "DC8" smd circle
			(at -27.880056 31.949898 180)
			(size 0.450088 0.450088)
			(layers "F.Cu" "F.Mask" "F.Paste")
			(net "GND")
		)
		(pad "DC9" smd circle
			(at -26.940002 31.949898 180)
			(size 0.450088 0.450088)
			(layers "F.Cu" "F.Mask" "F.Paste")
			(net "M_L_CPU1_SB_DQS_DN<3>")
		)
		(pad "DC10" smd circle
			(at -25.999948 31.949898 180)
			(size 0.450088 0.450088)
			(layers "F.Cu" "F.Mask" "F.Paste")
			(net "M_L_CPU1_SB_DQS_DN<8>")
		)
		(pad "DC11" smd circle
			(at -25.059894 31.949898 180)
			(size 0.450088 0.450088)
			(layers "F.Cu" "F.Mask" "F.Paste")
			(net "GND")
		)
		(pad "DC12" smd circle
			(at -24.120094 31.949898 180)
			(size 0.450088 0.450088)
			(layers "F.Cu" "F.Mask" "F.Paste")
			(net "M_H_CPU1_SB_DQS_DN<3>")
		)
		(pad "DC13" smd circle
			(at -23.18004 31.949898 180)
			(size 0.450088 0.450088)
			(layers "F.Cu" "F.Mask" "F.Paste")
			(net "GND")
		)
		(pad "DC14" smd circle
			(at -22.239986 31.949898 180)
			(size 0.450088 0.450088)
			(layers "F.Cu" "F.Mask" "F.Paste")
			(net "M_H_CPU1_SB_DQS_DN<8>")
		)
		(pad "DC15" smd circle
			(at -21.299932 31.949898 180)
			(size 0.450088 0.450088)
			(layers "F.Cu" "F.Mask" "F.Paste")
			(net "GND")
		)
		(pad "DC16" smd circle
			(at -20.359878 31.949898 180)
			(size 0.450088 0.450088)
			(layers "F.Cu" "F.Mask" "F.Paste")
			(net "M_J_CPU1_SB_DQS_DN<3>")
		)
		(pad "DC17" smd circle
			(at -19.420078 31.949898 180)
			(size 0.450088 0.450088)
			(layers "F.Cu" "F.Mask" "F.Paste")
			(net "M_J_CPU1_SB_DQS_DN<8>")
		)
		(pad "DC18" smd circle
			(at -18.480024 31.949898 180)
			(size 0.450088 0.450088)
			(layers "F.Cu" "F.Mask" "F.Paste")
			(net "GND")
		)
		(pad "DC19" smd circle
			(at -17.53997 31.949898 180)
			(size 0.450088 0.450088)
			(layers "F.Cu" "F.Mask" "F.Paste")
			(net "M_I_CPU1_SB_DQS_DN<3>")
		)
		(pad "DC20" smd circle
			(at -16.599916 31.949898 180)
			(size 0.450088 0.450088)
			(layers "F.Cu" "F.Mask" "F.Paste")
			(net "GND")
		)
		(pad "DC21" smd circle
			(at -15.660116 31.949898 180)
			(size 0.450088 0.450088)
			(layers "F.Cu" "F.Mask" "F.Paste")
			(net "M_I_CPU1_SB_DQS_DN<8>")
		)
		(pad "DC22" smd circle
			(at -14.720062 31.949898 180)
			(size 0.450088 0.450088)
			(layers "F.Cu" "F.Mask" "F.Paste")
			(net "GND")
		)
		(pad "DC23" smd circle
			(at -13.780008 31.949898 180)
			(size 0.450088 0.450088)
			(layers "F.Cu" "F.Mask" "F.Paste")
			(net "P5E_CPU1_P3_RX_DP<13>")
		)
		(pad "DC24" smd circle
			(at -12.839954 31.949898 180)
			(size 0.450088 0.450088)
			(layers "F.Cu" "F.Mask" "F.Paste")
			(net "P5E_CPU1_P3_RX_DN<13>")
		)
		(pad "DC25" smd circle
			(at -11.8999 31.949898 180)
			(size 0.450088 0.450088)
			(layers "F.Cu" "F.Mask" "F.Paste")
			(net "GND")
		)
		(pad "DC26" smd circle
			(at -10.9601 31.949898 180)
			(size 0.450088 0.450088)
			(layers "F.Cu" "F.Mask" "F.Paste")
			(net "P5E_CPU1_P3_RX_DP<10>")
		)
		(pad "DC27" smd circle
			(at -10.020046 31.949898 180)
			(size 0.450088 0.450088)
			(layers "F.Cu" "F.Mask" "F.Paste")
			(net "P5E_CPU1_P3_RX_DN<10>")
		)
		(pad "DC28" smd circle
			(at -9.079992 31.949898 180)
			(size 0.450088 0.450088)
			(layers "F.Cu" "F.Mask" "F.Paste")
			(net "GND")
		)
		(pad "DC29" smd circle
			(at -8.139938 31.949898 180)
			(size 0.450088 0.450088)
			(layers "F.Cu" "F.Mask" "F.Paste")
			(net "P5E_CPU1_P3_RX_DP<7>")
		)
		(pad "DC30" smd circle
			(at -7.199884 31.949898 180)
			(size 0.450088 0.450088)
			(layers "F.Cu" "F.Mask" "F.Paste")
			(net "P5E_CPU1_P3_RX_DN<7>")
		)
		(pad "DC31" smd circle
			(at -6.260084 31.949898 180)
			(size 0.450088 0.450088)
			(layers "F.Cu" "F.Mask" "F.Paste")
			(net "GND")
		)
		(pad "DC32" smd circle
			(at -5.32003 31.949898 180)
			(size 0.450088 0.450088)
			(layers "F.Cu" "F.Mask" "F.Paste")
			(net "P5E_CPU1_P3_RX_DP<4>")
		)
		(pad "DC33" smd circle
			(at -4.379976 31.949898 180)
			(size 0.450088 0.450088)
			(layers "F.Cu" "F.Mask" "F.Paste")
			(net "P5E_CPU1_P3_RX_DN<4>")
		)
		(pad "DC34" smd circle
			(at -3.439922 31.949898 180)
			(size 0.450088 0.450088)
			(layers "F.Cu" "F.Mask" "F.Paste")
			(net "GND")
		)
		(pad "DC35" smd circle
			(at -2.500122 31.949898 180)
			(size 0.450088 0.450088)
			(layers "F.Cu" "F.Mask" "F.Paste")
			(net "PVDDCR_CPU1_P1")
		)
		(pad "DC36" smd circle
			(at -1.560068 31.949898 180)
			(size 0.450088 0.450088)
			(layers "F.Cu" "F.Mask" "F.Paste")
			(net "PVDDCR_CPU1_P1")
		)
		(pad "DC40" smd circle
			(at 1.260094 31.949898 180)
			(size 0.450088 0.450088)
			(layers "F.Cu" "F.Mask" "F.Paste")
			(net "PVDDCR_CPU1_P1")
		)
		(pad "DC41" smd circle
			(at 2.199894 31.949898 180)
			(size 0.450088 0.450088)
			(layers "F.Cu" "F.Mask" "F.Paste")
			(net "PVDDCR_CPU1_P1")
		)
		(pad "DC42" smd circle
			(at 3.139948 31.949898 180)
			(size 0.450088 0.450088)
			(layers "F.Cu" "F.Mask" "F.Paste")
			(net "GND")
		)
		(pad "DC43" smd circle
			(at 4.080002 31.949898 180)
			(size 0.450088 0.450088)
			(layers "F.Cu" "F.Mask" "F.Paste")
			(net "P5E_CPU1_P1_TX_DN<11>")
		)
		(pad "DC44" smd circle
			(at 5.020056 31.949898 180)
			(size 0.450088 0.450088)
			(layers "F.Cu" "F.Mask" "F.Paste")
			(net "P5E_CPU1_P1_TX_DP<11>")
		)
		(pad "DC45" smd circle
			(at 5.96011 31.949898 180)
			(size 0.450088 0.450088)
			(layers "F.Cu" "F.Mask" "F.Paste")
			(net "GND")
		)
		(pad "DC46" smd circle
			(at 6.89991 31.949898 180)
			(size 0.450088 0.450088)
			(layers "F.Cu" "F.Mask" "F.Paste")
			(net "P5E_CPU1_P1_TX_DN<8>")
		)
		(pad "DC47" smd circle
			(at 7.839964 31.949898 180)
			(size 0.450088 0.450088)
			(layers "F.Cu" "F.Mask" "F.Paste")
			(net "P5E_CPU1_P1_TX_DP<8>")
		)
		(pad "DC48" smd circle
			(at 8.780018 31.949898 180)
			(size 0.450088 0.450088)
			(layers "F.Cu" "F.Mask" "F.Paste")
			(net "GND")
		)
		(pad "DC49" smd circle
			(at 9.720072 31.949898 180)
			(size 0.450088 0.450088)
			(layers "F.Cu" "F.Mask" "F.Paste")
			(net "P5E_CPU1_P1_TX_DN<5>")
		)
		(pad "DC50" smd circle
			(at 10.659872 31.949898 180)
			(size 0.450088 0.450088)
			(layers "F.Cu" "F.Mask" "F.Paste")
			(net "P5E_CPU1_P1_TX_DP<5>")
		)
		(pad "DC51" smd circle
			(at 11.599926 31.949898 180)
			(size 0.450088 0.450088)
			(layers "F.Cu" "F.Mask" "F.Paste")
			(net "GND")
		)
		(pad "DC52" smd circle
			(at 12.53998 31.949898 180)
			(size 0.450088 0.450088)
			(layers "F.Cu" "F.Mask" "F.Paste")
			(net "P5E_CPU1_P1_TX_DN<2>")
		)
		(pad "DC53" smd circle
			(at 13.480034 31.949898 180)
			(size 0.450088 0.450088)
			(layers "F.Cu" "F.Mask" "F.Paste")
			(net "P5E_CPU1_P1_TX_DP<2>")
		)
		(pad "DC54" smd circle
			(at 14.420088 31.949898 180)
			(size 0.450088 0.450088)
			(layers "F.Cu" "F.Mask" "F.Paste")
			(net "GND")
		)
		(pad "DC55" smd circle
			(at 15.359888 31.949898 180)
			(size 0.450088 0.450088)
			(layers "F.Cu" "F.Mask" "F.Paste")
			(net "M_C_CPU1_SB_DQS_DN<8>")
		)
		(pad "DC56" smd circle
			(at 16.299942 31.949898 180)
			(size 0.450088 0.450088)
			(layers "F.Cu" "F.Mask" "F.Paste")
			(net "GND")
		)
		(pad "DC57" smd circle
			(at 17.239996 31.949898 180)
			(size 0.450088 0.450088)
			(layers "F.Cu" "F.Mask" "F.Paste")
			(net "M_C_CPU1_SB_DQS_DN<3>")
		)
		(pad "DC58" smd circle
			(at 18.18005 31.949898 180)
			(size 0.450088 0.450088)
			(layers "F.Cu" "F.Mask" "F.Paste")
			(net "GND")
		)
		(pad "DC59" smd circle
			(at 19.120104 31.949898 180)
			(size 0.450088 0.450088)
			(layers "F.Cu" "F.Mask" "F.Paste")
			(net "M_D_CPU1_SB_DQS_DN<8>")
		)
		(pad "DC60" smd circle
			(at 20.059904 31.949898 180)
			(size 0.450088 0.450088)
			(layers "F.Cu" "F.Mask" "F.Paste")
			(net "M_D_CPU1_SB_DQS_DN<3>")
		)
		(pad "DC61" smd circle
			(at 20.999958 31.949898 180)
			(size 0.450088 0.450088)
			(layers "F.Cu" "F.Mask" "F.Paste")
			(net "GND")
		)
		(pad "DC62" smd circle
			(at 21.940012 31.949898 180)
			(size 0.450088 0.450088)
			(layers "F.Cu" "F.Mask" "F.Paste")
			(net "M_B_CPU1_SB_DQS_DN<8>")
		)
		(pad "DC63" smd circle
			(at 22.880066 31.949898 180)
			(size 0.450088 0.450088)
			(layers "F.Cu" "F.Mask" "F.Paste")
			(net "GND")
		)
		(pad "DC64" smd circle
			(at 23.82012 31.949898 180)
			(size 0.450088 0.450088)
			(layers "F.Cu" "F.Mask" "F.Paste")
			(net "M_B_CPU1_SB_DQS_DN<3>")
		)
		(pad "DC65" smd circle
			(at 24.75992 31.949898 180)
			(size 0.450088 0.450088)
			(layers "F.Cu" "F.Mask" "F.Paste")
			(net "GND")
		)
		(pad "DC66" smd circle
			(at 25.699974 31.949898 180)
			(size 0.450088 0.450088)
			(layers "F.Cu" "F.Mask" "F.Paste")
			(net "M_F_CPU1_SB_DQS_DN<8>")
		)
		(pad "DC67" smd circle
			(at 26.640028 31.949898 180)
			(size 0.450088 0.450088)
			(layers "F.Cu" "F.Mask" "F.Paste")
			(net "M_F_CPU1_SB_DQS_DN<3>")
		)
		(pad "DC68" smd circle
			(at 27.580082 31.949898 180)
			(size 0.450088 0.450088)
			(layers "F.Cu" "F.Mask" "F.Paste")
			(net "GND")
		)
		(pad "DC69" smd circle
			(at 28.519882 31.949898 180)
			(size 0.450088 0.450088)
			(layers "F.Cu" "F.Mask" "F.Paste")
			(net "M_E_CPU1_SB_DQS_DN<8>")
		)
		(pad "DC70" smd circle
			(at 29.459936 31.949898 180)
			(size 0.450088 0.450088)
			(layers "F.Cu" "F.Mask" "F.Paste")
			(net "GND")
		)
		(pad "DC71" smd circle
			(at 30.39999 31.949898 180)
			(size 0.450088 0.450088)
			(layers "F.Cu" "F.Mask" "F.Paste")
			(net "M_E_CPU1_SB_DQS_DN<3>")
		)
		(pad "DC72" smd circle
			(at 31.340044 31.949898 180)
			(size 0.450088 0.450088)
			(layers "F.Cu" "F.Mask" "F.Paste")
			(net "GND")
		)
		(pad "DC73" smd circle
			(at 32.280098 31.949898 180)
			(size 0.450088 0.450088)
			(layers "F.Cu" "F.Mask" "F.Paste")
			(net "M_A_CPU1_SB_DQS_DN<8>")
		)
		(pad "DC74" smd circle
			(at 33.219898 31.949898 180)
			(size 0.450088 0.450088)
			(layers "F.Cu" "F.Mask" "F.Paste")
			(net "M_A_CPU1_SB_DQS_DN<3>")
		)
		(pad "DC75" smd circle
			(at 34.159952 31.949898 180)
			(size 0.450088 0.450088)
			(layers "F.Cu" "F.Mask" "F.Paste")
			(net "GND")
		)
		(pad "DD2" smd circle
			(at -33.990026 32.759904 180)
			(size 0.450088 0.450088)
			(layers "F.Cu" "F.Mask" "F.Paste")
			(net "M_G_CPU1_SB_DQ<28>")
		)
		(pad "DD3" smd circle
			(at -33.049972 32.759904 180)
			(size 0.450088 0.450088)
			(layers "F.Cu" "F.Mask" "F.Paste")
			(net "GND")
		)
		(pad "DD4" smd circle
			(at -32.109918 32.759904 180)
			(size 0.450088 0.450088)
			(layers "F.Cu" "F.Mask" "F.Paste")
			(net "M_G_CPU1_SB_DQS_DP<8>")
		)
		(pad "DD5" smd circle
			(at -31.170118 32.759904 180)
			(size 0.450088 0.450088)
			(layers "F.Cu" "F.Mask" "F.Paste")
			(net "GND")
		)
		(pad "DD6" smd circle
			(at -30.230064 32.759904 180)
			(size 0.450088 0.450088)
			(layers "F.Cu" "F.Mask" "F.Paste")
			(net "M_K_CPU1_SB_DQ<28>")
		)
		(pad "DD7" smd circle
			(at -29.29001 32.759904 180)
			(size 0.450088 0.450088)
			(layers "F.Cu" "F.Mask" "F.Paste")
			(net "M_K_CPU1_SB_DQS_DP<8>")
		)
		(pad "DD8" smd circle
			(at -28.349956 32.759904 180)
			(size 0.450088 0.450088)
			(layers "F.Cu" "F.Mask" "F.Paste")
			(net "GND")
		)
		(pad "DD9" smd circle
			(at -27.409902 32.759904 180)
			(size 0.450088 0.450088)
			(layers "F.Cu" "F.Mask" "F.Paste")
			(net "M_L_CPU1_SB_DQ<28>")
		)
		(pad "DD10" smd circle
			(at -26.470102 32.759904 180)
			(size 0.450088 0.450088)
			(layers "F.Cu" "F.Mask" "F.Paste")
			(net "GND")
		)
		(pad "DD11" smd circle
			(at -25.530048 32.759904 180)
			(size 0.450088 0.450088)
			(layers "F.Cu" "F.Mask" "F.Paste")
			(net "M_L_CPU1_SB_DQS_DP<8>")
		)
		(pad "DD12" smd circle
			(at -24.589994 32.759904 180)
			(size 0.450088 0.450088)
			(layers "F.Cu" "F.Mask" "F.Paste")
			(net "GND")
		)
		(pad "DD13" smd circle
			(at -23.64994 32.759904 180)
			(size 0.450088 0.450088)
			(layers "F.Cu" "F.Mask" "F.Paste")
			(net "M_H_CPU1_SB_DQ<28>")
		)
		(pad "DD14" smd circle
			(at -22.709886 32.759904 180)
			(size 0.450088 0.450088)
			(layers "F.Cu" "F.Mask" "F.Paste")
			(net "M_H_CPU1_SB_DQS_DP<8>")
		)
		(pad "DD15" smd circle
			(at -21.770086 32.759904 180)
			(size 0.450088 0.450088)
			(layers "F.Cu" "F.Mask" "F.Paste")
			(net "GND")
		)
		(pad "DD16" smd circle
			(at -20.830032 32.759904 180)
			(size 0.450088 0.450088)
			(layers "F.Cu" "F.Mask" "F.Paste")
			(net "M_J_CPU1_SB_DQ<28>")
		)
		(pad "DD17" smd circle
			(at -19.889978 32.759904 180)
			(size 0.450088 0.450088)
			(layers "F.Cu" "F.Mask" "F.Paste")
			(net "GND")
		)
		(pad "DD18" smd circle
			(at -18.949924 32.759904 180)
			(size 0.450088 0.450088)
			(layers "F.Cu" "F.Mask" "F.Paste")
			(net "M_J_CPU1_SB_DQS_DP<8>")
		)
		(pad "DD19" smd circle
			(at -18.010124 32.759904 180)
			(size 0.450088 0.450088)
			(layers "F.Cu" "F.Mask" "F.Paste")
			(net "GND")
		)
		(pad "DD20" smd circle
			(at -17.07007 32.759904 180)
			(size 0.450088 0.450088)
			(layers "F.Cu" "F.Mask" "F.Paste")
			(net "M_I_CPU1_SB_DQ<28>")
		)
		(pad "DD21" smd circle
			(at -16.130016 32.759904 180)
			(size 0.450088 0.450088)
			(layers "F.Cu" "F.Mask" "F.Paste")
			(net "M_I_CPU1_SB_DQS_DP<8>")
		)
		(pad "DD22" smd circle
			(at -15.189962 32.759904 180)
			(size 0.450088 0.450088)
			(layers "F.Cu" "F.Mask" "F.Paste")
			(net "PVDDCR_CPU1_P1")
		)
		(pad "DD23" smd circle
			(at -14.249908 32.759904 180)
			(size 0.450088 0.450088)
			(layers "F.Cu" "F.Mask" "F.Paste")
			(net "GND")
		)
		(pad "DD24" smd circle
			(at -13.310108 32.759904 180)
			(size 0.450088 0.450088)
			(layers "F.Cu" "F.Mask" "F.Paste")
			(net "GND")
		)
		(pad "DD25" smd circle
			(at -12.370054 32.759904 180)
			(size 0.450088 0.450088)
			(layers "F.Cu" "F.Mask" "F.Paste")
			(net "PVDDCR_CPU1_P1")
		)
	)
)
